FILE_TYPE = CONNECTIVITY;
{Allegro Design Entry HDL 17.2-2016 S066 (3851973) 4/6/2020}
"PAGE_NUMBER" = 22;
0"NC";
END.
